# SCM (Grand Teton) — schematic netlist excerpt (pin names and nets, part order shuffled) for the footprints in the layout excerpt that follows; sources: Cadence DE-HDL packaged netlist, KiCad conversion of 12092022_DA0F0TMDCD0_F0T_Management_Board_D_brd_V3_OCP.brd

R903  Q_RES  0 5% CHIP  pkg 0402LF  page 31 : A = UART_6_BMC_TXD ; B = UART_6_BMC_TXD_R
R510  Q_RES  33.2 1% CHIP  pkg 0402LF  page 32 : A = JTAG_SCM_TCK ; B = JTAG_SCM_PLD_TCK

(kicad_pcb
	(version 20260206)
	(generator "pcbnew")
	(generator_version "10.0")
	(general
		(thickness 1.6)
		(legacy_teardrops no)
	)
	(paper "A4")
	(title_block
		(title "12092022_DA0F0TMDCD0_F0T_Management_Board_D_brd_V3_OCP.brd")
		(comment 1 "Grand Teton / footprints 318-319 of 1440")
	)
	(layers
		(0 "F.Cu" signal "TOP")
		(4 "In1.Cu" signal "GND")
		(6 "In2.Cu" signal "IN1")
		(8 "In3.Cu" signal "GND1")
		(10 "In4.Cu" signal "IN2")
		(12 "In5.Cu" signal "VCC")
		(14 "In6.Cu" signal "VCC1")
		(16 "In7.Cu" signal "IN3")
		(18 "In8.Cu" signal "GND2")
		(20 "In9.Cu" signal "IN4")
		(22 "In10.Cu" signal "GND3")
		(2 "B.Cu" signal "BOTTOM")
		(9 "F.Adhes" user "F.Adhesive")
		(11 "B.Adhes" user "B.Adhesive")
		(13 "F.Paste" user "Package Geometry/Pastemask Top")
		(15 "B.Paste" user "Package Geometry/Pastemask Bottom")
		(5 "F.SilkS" user "Ref Des/Silkscreen Top")
		(7 "B.SilkS" user "Ref Des/Silkscreen Bottom")
		(1 "F.Mask" user "Board Geometry/Soldermask Top")
		(3 "B.Mask" user "Board Geometry/Soldermask Bottom")
		(17 "Dwgs.User" user "User.Drawings")
		(19 "Cmts.User" user "User.Comments")
		(21 "Eco1.User" user "User.Eco1")
		(23 "Eco2.User" user "User.Eco2")
		(25 "Edge.Cuts" user "Board Geometry/Outline")
		(27 "Margin" user)
		(31 "F.CrtYd" user "Package Geometry/Place Bound Top")
		(29 "B.CrtYd" user "Package Geometry/Place Bound Bottom")
		(35 "F.Fab" user "Ref Des/Assembly Top")
		(33 "B.Fab" user "Ref Des/Assembly Bottom")
	)
	(footprint ""
		(layer "F.Cu")
		(at 16.564864 -57.7342 90)
		(property "Reference" "R903"
			(at 0 0 90)
			(layer "F.SilkS")
			(hide yes)
			(effects
				(font
					(size 1.27 1.27)
				)
			)
		)
		(property "Value" ""
			(at 0 0 90)
			(layer "F.Fab")
			(effects
				(font
					(size 1.27 1.27)
				)
			)
		)
		(duplicate_pad_numbers_are_jumpers no)
		(fp_line
			(start 0.7874 -0.4064)
			(end 0.7874 0.4064)
			(stroke
				(width 0.1524)
				(type default)
			)
			(layer "F.SilkS")
		)
		(fp_line
			(start -0.7874 -0.4064)
			(end 0.7874 -0.4064)
			(stroke
				(width 0.1524)
				(type default)
			)
			(layer "F.SilkS")
		)
		(fp_line
			(start 0.7874 0.4064)
			(end -0.7874 0.4064)
			(stroke
				(width 0.1524)
				(type default)
			)
			(layer "F.SilkS")
		)
		(fp_line
			(start -0.7874 0.4064)
			(end -0.7874 -0.4064)
			(stroke
				(width 0.1524)
				(type default)
			)
			(layer "F.SilkS")
		)
		(fp_line
			(start -0.12065 -0.305054)
			(end -0.12065 -0.2794)
			(stroke
				(width 0.1)
				(type default)
			)
			(layer "F.Fab")
		)
		(fp_line
			(start -0.67945 -0.305054)
			(end -0.12065 -0.305054)
			(stroke
				(width 0.1)
				(type default)
			)
			(layer "F.Fab")
		)
		(fp_line
			(start 0.67945 -0.3048)
			(end 0.67945 0.3048)
			(stroke
				(width 0.1)
				(type default)
			)
			(layer "F.Fab")
		)
		(fp_line
			(start 0.12065 -0.3048)
			(end 0.67945 -0.3048)
			(stroke
				(width 0.1)
				(type default)
			)
			(layer "F.Fab")
		)
		(fp_line
			(start 0.12065 -0.2794)
			(end 0.12065 -0.3048)
			(stroke
				(width 0.1)
				(type default)
			)
			(layer "F.Fab")
		)
		(fp_line
			(start -0.12065 -0.2794)
			(end 0.12065 -0.2794)
			(stroke
				(width 0.1)
				(type default)
			)
			(layer "F.Fab")
		)
		(fp_line
			(start 0.120396 0.2794)
			(end -0.12065 0.2794)
			(stroke
				(width 0.1)
				(type default)
			)
			(layer "F.Fab")
		)
		(fp_line
			(start -0.12065 0.2794)
			(end -0.12065 0.3048)
			(stroke
				(width 0.1)
				(type default)
			)
			(layer "F.Fab")
		)
		(fp_line
			(start 0.67945 0.3048)
			(end 0.120396 0.3048)
			(stroke
				(width 0.1)
				(type default)
			)
			(layer "F.Fab")
		)
		(fp_line
			(start 0.120396 0.3048)
			(end 0.120396 0.2794)
			(stroke
				(width 0.1)
				(type default)
			)
			(layer "F.Fab")
		)
		(fp_line
			(start -0.12065 0.3048)
			(end -0.67945 0.3048)
			(stroke
				(width 0.1)
				(type default)
			)
			(layer "F.Fab")
		)
		(fp_line
			(start -0.67945 0.3048)
			(end -0.67945 -0.305054)
			(stroke
				(width 0.1)
				(type default)
			)
			(layer "F.Fab")
		)
		(pad "1" smd circle
			(at -0.40005 0 90)
			(size 0 0)
			(layers "F.Cu" "F.Mask" "F.Paste")
			(net "UART_6_BMC_TXD")
		)
		(pad "2" smd circle
			(at 0.40005 0 90)
			(size 0 0)
			(layers "F.Cu" "F.Mask" "F.Paste")
			(net "UART_6_BMC_TXD_R")
		)
	)
	(footprint ""
		(layer "F.Cu")
		(at 68.5292 -26.3906 -90)
		(property "Reference" "R510"
			(at 0 0 270)
			(layer "F.SilkS")
			(hide yes)
			(effects
				(font
					(size 1.27 1.27)
				)
			)
		)
		(property "Value" ""
			(at 0 0 270)
			(layer "F.Fab")
			(effects
				(font
					(size 1.27 1.27)
				)
			)
		)
		(duplicate_pad_numbers_are_jumpers no)
		(fp_line
			(start -0.7874 0.4064)
			(end -0.7874 -0.4064)
			(stroke
				(width 0.1524)
				(type default)
			)
			(layer "F.SilkS")
		)
		(fp_line
			(start 0.7874 0.4064)
			(end -0.7874 0.4064)
			(stroke
				(width 0.1524)
				(type default)
			)
			(layer "F.SilkS")
		)
		(fp_line
			(start -0.7874 -0.4064)
			(end 0.7874 -0.4064)
			(stroke
				(width 0.1524)
				(type default)
			)
			(layer "F.SilkS")
		)
		(fp_line
			(start 0.7874 -0.4064)
			(end 0.7874 0.4064)
			(stroke
				(width 0.1524)
				(type default)
			)
			(layer "F.SilkS")
		)
		(fp_line
			(start -0.67945 0.3048)
			(end -0.67945 -0.305054)
			(stroke
				(width 0.1)
				(type default)
			)
			(layer "F.Fab")
		)
		(fp_line
			(start -0.12065 0.3048)
			(end -0.67945 0.3048)
			(stroke
				(width 0.1)
				(type default)
			)
			(layer "F.Fab")
		)
		(fp_line
			(start 0.120396 0.3048)
			(end 0.120396 0.2794)
			(stroke
				(width 0.1)
				(type default)
			)
			(layer "F.Fab")
		)
		(fp_line
			(start 0.67945 0.3048)
			(end 0.120396 0.3048)
			(stroke
				(width 0.1)
				(type default)
			)
			(layer "F.Fab")
		)
		(fp_line
			(start -0.12065 0.2794)
			(end -0.12065 0.3048)
			(stroke
				(width 0.1)
				(type default)
			)
			(layer "F.Fab")
		)
		(fp_line
			(start 0.120396 0.2794)
			(end -0.12065 0.2794)
			(stroke
				(width 0.1)
				(type default)
			)
			(layer "F.Fab")
		)
		(fp_line
			(start -0.12065 -0.2794)
			(end 0.12065 -0.2794)
			(stroke
				(width 0.1)
				(type default)
			)
			(layer "F.Fab")
		)
		(fp_line
			(start 0.12065 -0.2794)
			(end 0.12065 -0.3048)
			(stroke
				(width 0.1)
				(type default)
			)
			(layer "F.Fab")
		)
		(fp_line
			(start 0.12065 -0.3048)
			(end 0.67945 -0.3048)
			(stroke
				(width 0.1)
				(type default)
			)
			(layer "F.Fab")
		)
		(fp_line
			(start 0.67945 -0.3048)
			(end 0.67945 0.3048)
			(stroke
				(width 0.1)
				(type default)
			)
			(layer "F.Fab")
		)
		(fp_line
			(start -0.67945 -0.305054)
			(end -0.12065 -0.305054)
			(stroke
				(width 0.1)
				(type default)
			)
			(layer "F.Fab")
		)
		(fp_line
			(start -0.12065 -0.305054)
			(end -0.12065 -0.2794)
			(stroke
				(width 0.1)
				(type default)
			)
			(layer "F.Fab")
		)
		(pad "1" smd circle
			(at -0.40005 0 270)
			(size 0 0)
			(layers "F.Cu" "F.Mask" "F.Paste")
			(net "JTAG_SCM_TCK")
		)
		(pad "2" smd circle
			(at 0.40005 0 270)
			(size 0 0)
			(layers "F.Cu" "F.Mask" "F.Paste")
			(net "JTAG_SCM_PLD_TCK")
		)
	)
)
